FILE_TYPE = MULTI_PHYS_TABLE;
PART 'CONN12_G98257001'
{===================================================================================================================================================================================================}
:PACK_TYPE | MATERIAL | PART_NUMBER     = EnvComp | PART_NUMBER  | JEDEC_TYPE          | DESCRIPTION                               | CLASS | COMPONENT_TYPE | HEIGHT     | LEAD_LENGTH   | SPEED_URL | Status |RPL| AML | Bus_Unit | Days ;
{===================================================================================================================================================================================================}
'THMT'     | 'CONN'   | 'G98257-001'(!) = 'YES;YES;CNC;CNC;ok;VLD' | 'G98257-001' | 'CONN12_G98257001'  | 'CONN_HDR,2X2,PLG,RA,2.00mm,6PF,BK'       | 'IO'  | 'PRESSFIT'     | '0.453 IN' | '0.118' | 'http://speed.intel.com:8081/speed/module/pdm/item/pdm_item_detail_direct.asp?item_cde=G98257-001&item_rev=01&url_param=unused' | 'Design' | 'NO' | '1' | 'SMO_BOARDS' | '???' 
'THMT'     | 'EMPTY'  | 'G98257-001'(!) = 'YES;YES;CNC;CNC;ok;VLD' | 'G98257-001' | 'CONN12_G98257001'  | 'CONN_HDR,2X2,PLG,RA,2.00mm,6PF,BK'       | 'IO'  | 'PRESSFIT'     | '0.453 IN' | '0.118' | 'http://speed.intel.com:8081/speed/module/pdm/item/pdm_item_detail_direct.asp?item_cde=G98257-001&item_rev=01&url_param=unused' | 'Design' | 'NO' | '1' | 'SMO_BOARDS' | '???' 
END_PART
END.
